(kicad_pcb
	(version 20260206)
	(generator "pcbnew")
	(generator_version "10.0")
	(general
		(thickness 1.6)
		(legacy_teardrops no)
	)
	(paper "A4")
	(title_block
		(title "04192023_DAF0TMB3IC0_F0TG_MB_C_brd_V02_OCP.brd")
		(comment 1 "Grand Teton / footprints 6531-6538 of 8354")
	)
	(layers
		(0 "F.Cu" signal "TOP")
		(4 "In1.Cu" signal "GND")
		(6 "In2.Cu" signal "IN1")
		(8 "In3.Cu" signal "GND1")
		(10 "In4.Cu" signal "IN2")
		(12 "In5.Cu" signal "GND2")
		(14 "In6.Cu" signal "IN3")
		(16 "In7.Cu" signal "GND3")
		(18 "In8.Cu" signal "VCC")
		(20 "In9.Cu" signal "VCC1")
		(22 "In10.Cu" signal "GND4")
		(24 "In11.Cu" signal "IN4")
		(26 "In12.Cu" signal "GND5")
		(28 "In13.Cu" signal "IN5")
		(30 "In14.Cu" signal "GND6")
		(32 "In15.Cu" signal "IN6")
		(34 "In16.Cu" signal "GND7")
		(2 "B.Cu" signal "BOTTOM")
		(9 "F.Adhes" user "F.Adhesive")
		(11 "B.Adhes" user "B.Adhesive")
		(13 "F.Paste" user "Package Geometry/Pastemask Top")
		(15 "B.Paste" user "Package Geometry/Pastemask Bottom")
		(5 "F.SilkS" user "Ref Des/Silkscreen Top")
		(7 "B.SilkS" user "Ref Des/Silkscreen Bottom")
		(1 "F.Mask" user "Board Geometry/Soldermask Top")
		(3 "B.Mask" user "Board Geometry/Soldermask Bottom")
		(17 "Dwgs.User" user "User.Drawings")
		(19 "Cmts.User" user "User.Comments")
		(21 "Eco1.User" user "User.Eco1")
		(23 "Eco2.User" user "User.Eco2")
		(25 "Edge.Cuts" user "Board Geometry/Outline")
		(27 "Margin" user)
		(31 "F.CrtYd" user "Package Geometry/Place Bound Top")
		(29 "B.CrtYd" user "Package Geometry/Place Bound Bottom")
		(35 "F.Fab" user "Ref Des/Assembly Top")
		(33 "B.Fab" user "Ref Des/Assembly Bottom")
	)
	(footprint ""
		(layer "B.Cu")
		(at 240.469928 -289.066732 90)
		(property "Reference" "R6506"
			(at 0 0 90)
			(layer "B.SilkS")
			(hide yes)
			(effects
				(font
					(size 1.27 1.27)
				)
				(justify mirror)
			)
		)
		(property "Value" ""
			(at 0 0 90)
			(layer "B.Fab")
			(effects
				(font
					(size 1.27 1.27)
				)
				(justify mirror)
			)
		)
		(duplicate_pad_numbers_are_jumpers no)
		(fp_line
			(start 0.7874 -0.4064)
			(end -0.7874 -0.4064)
			(stroke
				(width 0.1524)
				(type default)
			)
			(layer "B.SilkS")
		)
		(fp_line
			(start -0.7874 -0.4064)
			(end -0.7874 0.4064)
			(stroke
				(width 0.1524)
				(type default)
			)
			(layer "B.SilkS")
		)
		(fp_line
			(start 0.7874 0.4064)
			(end 0.7874 -0.4064)
			(stroke
				(width 0.1524)
				(type default)
			)
			(layer "B.SilkS")
		)
		(fp_line
			(start -0.7874 0.4064)
			(end 0.7874 0.4064)
			(stroke
				(width 0.1524)
				(type default)
			)
			(layer "B.SilkS")
		)
		(fp_line
			(start 0.67945 -0.305054)
			(end 0.12065 -0.305054)
			(stroke
				(width 0.1)
				(type default)
			)
			(layer "B.Fab")
		)
		(fp_line
			(start 0.12065 -0.305054)
			(end 0.12065 -0.2794)
			(stroke
				(width 0.1)
				(type default)
			)
			(layer "B.Fab")
		)
		(fp_line
			(start -0.12065 -0.3048)
			(end -0.67945 -0.3048)
			(stroke
				(width 0.1)
				(type default)
			)
			(layer "B.Fab")
		)
		(fp_line
			(start -0.67945 -0.3048)
			(end -0.67945 0.3048)
			(stroke
				(width 0.1)
				(type default)
			)
			(layer "B.Fab")
		)
		(fp_line
			(start 0.12065 -0.2794)
			(end -0.12065 -0.2794)
			(stroke
				(width 0.1)
				(type default)
			)
			(layer "B.Fab")
		)
		(fp_line
			(start -0.12065 -0.2794)
			(end -0.12065 -0.3048)
			(stroke
				(width 0.1)
				(type default)
			)
			(layer "B.Fab")
		)
		(fp_line
			(start 0.12065 0.2794)
			(end 0.12065 0.3048)
			(stroke
				(width 0.1)
				(type default)
			)
			(layer "B.Fab")
		)
		(fp_line
			(start -0.120396 0.2794)
			(end 0.12065 0.2794)
			(stroke
				(width 0.1)
				(type default)
			)
			(layer "B.Fab")
		)
		(fp_line
			(start 0.67945 0.3048)
			(end 0.67945 -0.305054)
			(stroke
				(width 0.1)
				(type default)
			)
			(layer "B.Fab")
		)
		(fp_line
			(start 0.12065 0.3048)
			(end 0.67945 0.3048)
			(stroke
				(width 0.1)
				(type default)
			)
			(layer "B.Fab")
		)
		(fp_line
			(start -0.120396 0.3048)
			(end -0.120396 0.2794)
			(stroke
				(width 0.1)
				(type default)
			)
			(layer "B.Fab")
		)
		(fp_line
			(start -0.67945 0.3048)
			(end -0.120396 0.3048)
			(stroke
				(width 0.1)
				(type default)
			)
			(layer "B.Fab")
		)
		(pad "1" smd circle
			(at 0.40005 0 270)
			(size 0 0)
			(layers "B.Cu" "B.Mask" "B.Paste")
			(net "PWRGD_P1V8_RETIMER_CPU0")
		)
		(pad "2" smd circle
			(at -0.40005 0 270)
			(size 0 0)
			(layers "B.Cu" "B.Mask" "B.Paste")
			(net "FM_PWRGD_P1V8_RETIMER_CPU0")
		)
	)
	(footprint ""
		(layer "B.Cu")
		(at 327.657206 -416.899344 90)
		(property "Reference" "C6547"
			(at 0 0 90)
			(layer "B.SilkS")
			(hide yes)
			(effects
				(font
					(size 1.27 1.27)
				)
				(justify mirror)
			)
		)
		(property "Value" ""
			(at 0 0 90)
			(layer "B.Fab")
			(effects
				(font
					(size 1.27 1.27)
				)
				(justify mirror)
			)
		)
		(duplicate_pad_numbers_are_jumpers no)
		(fp_line
			(start 0.299974 -0.150114)
			(end -0.299974 -0.150114)
			(stroke
				(width 0.1)
				(type default)
			)
			(layer "B.Fab")
		)
		(fp_line
			(start -0.299974 -0.150114)
			(end -0.299974 0.150114)
			(stroke
				(width 0.1)
				(type default)
			)
			(layer "B.Fab")
		)
		(fp_line
			(start 0.299974 0.150114)
			(end 0.299974 -0.150114)
			(stroke
				(width 0.1)
				(type default)
			)
			(layer "B.Fab")
		)
		(fp_line
			(start -0.299974 0.150114)
			(end 0.299974 0.150114)
			(stroke
				(width 0.1)
				(type default)
			)
			(layer "B.Fab")
		)
		(pad "1" smd rect
			(at 0.2667 0 270)
			(size 0.3048 0.381)
			(layers "B.Cu" "B.Mask" "B.Paste")
			(net "P5E_CPU0_P1_TX_BUF_C_DP<7>")
		)
		(pad "2" smd rect
			(at -0.2667 0 270)
			(size 0.3048 0.381)
			(layers "B.Cu" "B.Mask" "B.Paste")
			(net "P5E_CPU0_P1_TX_BUF_DP<7>")
		)
	)
	(footprint ""
		(layer "B.Cu")
		(at 237.617 -249.555)
		(property "Reference" "R1156"
			(at 0 0 0)
			(layer "B.SilkS")
			(hide yes)
			(effects
				(font
					(size 1.27 1.27)
				)
				(justify mirror)
			)
		)
		(property "Value" ""
			(at 0 0 0)
			(layer "B.Fab")
			(effects
				(font
					(size 1.27 1.27)
				)
				(justify mirror)
			)
		)
		(duplicate_pad_numbers_are_jumpers no)
		(fp_line
			(start -0.7874 -0.4064)
			(end -0.7874 0.4064)
			(stroke
				(width 0.1524)
				(type default)
			)
			(layer "B.SilkS")
		)
		(fp_line
			(start -0.7874 0.4064)
			(end 0.7874 0.4064)
			(stroke
				(width 0.1524)
				(type default)
			)
			(layer "B.SilkS")
		)
		(fp_line
			(start 0.7874 -0.4064)
			(end -0.7874 -0.4064)
			(stroke
				(width 0.1524)
				(type default)
			)
			(layer "B.SilkS")
		)
		(fp_line
			(start 0.7874 0.4064)
			(end 0.7874 -0.4064)
			(stroke
				(width 0.1524)
				(type default)
			)
			(layer "B.SilkS")
		)
		(fp_line
			(start -0.67945 -0.3048)
			(end -0.67945 0.3048)
			(stroke
				(width 0.1)
				(type default)
			)
			(layer "B.Fab")
		)
		(fp_line
			(start -0.67945 0.3048)
			(end -0.120396 0.3048)
			(stroke
				(width 0.1)
				(type default)
			)
			(layer "B.Fab")
		)
		(fp_line
			(start -0.12065 -0.3048)
			(end -0.67945 -0.3048)
			(stroke
				(width 0.1)
				(type default)
			)
			(layer "B.Fab")
		)
		(fp_line
			(start -0.12065 -0.2794)
			(end -0.12065 -0.3048)
			(stroke
				(width 0.1)
				(type default)
			)
			(layer "B.Fab")
		)
		(fp_line
			(start -0.120396 0.2794)
			(end 0.12065 0.2794)
			(stroke
				(width 0.1)
				(type default)
			)
			(layer "B.Fab")
		)
		(fp_line
			(start -0.120396 0.3048)
			(end -0.120396 0.2794)
			(stroke
				(width 0.1)
				(type default)
			)
			(layer "B.Fab")
		)
		(fp_line
			(start 0.12065 -0.305054)
			(end 0.12065 -0.2794)
			(stroke
				(width 0.1)
				(type default)
			)
			(layer "B.Fab")
		)
		(fp_line
			(start 0.12065 -0.2794)
			(end -0.12065 -0.2794)
			(stroke
				(width 0.1)
				(type default)
			)
			(layer "B.Fab")
		)
		(fp_line
			(start 0.12065 0.2794)
			(end 0.12065 0.3048)
			(stroke
				(width 0.1)
				(type default)
			)
			(layer "B.Fab")
		)
		(fp_line
			(start 0.12065 0.3048)
			(end 0.67945 0.3048)
			(stroke
				(width 0.1)
				(type default)
			)
			(layer "B.Fab")
		)
		(fp_line
			(start 0.67945 -0.305054)
			(end 0.12065 -0.305054)
			(stroke
				(width 0.1)
				(type default)
			)
			(layer "B.Fab")
		)
		(fp_line
			(start 0.67945 0.3048)
			(end 0.67945 -0.305054)
			(stroke
				(width 0.1)
				(type default)
			)
			(layer "B.Fab")
		)
		(pad "1" smd rect
			(at 0.40005 0)
			(size 0.4572 0.508)
			(layers "B.Cu" "B.Mask" "B.Paste")
			(net "SMB_APML_CPU0_R_SCL")
		)
		(pad "2" smd rect
			(at -0.40005 0)
			(size 0.4572 0.508)
			(layers "B.Cu" "B.Mask" "B.Paste")
			(net "SMB_APML_CPU0_SCL")
		)
	)
	(footprint ""
		(layer "B.Cu")
		(at 98.592386 -256.734564 180)
		(property "Reference" "C2104"
			(at 0 0 0)
			(layer "B.SilkS")
			(hide yes)
			(effects
				(font
					(size 1.27 1.27)
				)
				(justify mirror)
			)
		)
		(property "Value" ""
			(at 0 0 0)
			(layer "B.Fab")
			(effects
				(font
					(size 1.27 1.27)
				)
				(justify mirror)
			)
		)
		(duplicate_pad_numbers_are_jumpers no)
		(fp_line
			(start 0.7874 0.4064)
			(end 0.7874 -0.4064)
			(stroke
				(width 0.1524)
				(type default)
			)
			(layer "B.SilkS")
		)
		(fp_line
			(start 0.7874 -0.4064)
			(end -0.7874 -0.4064)
			(stroke
				(width 0.1524)
				(type default)
			)
			(layer "B.SilkS")
		)
		(fp_line
			(start -0.7874 0.4064)
			(end 0.7874 0.4064)
			(stroke
				(width 0.1524)
				(type default)
			)
			(layer "B.SilkS")
		)
		(fp_line
			(start -0.7874 -0.4064)
			(end -0.7874 0.4064)
			(stroke
				(width 0.1524)
				(type default)
			)
			(layer "B.SilkS")
		)
		(fp_line
			(start 0.67945 0.3048)
			(end 0.67945 -0.305054)
			(stroke
				(width 0.1)
				(type default)
			)
			(layer "B.Fab")
		)
		(fp_line
			(start 0.67945 -0.305054)
			(end 0.12065 -0.305054)
			(stroke
				(width 0.1)
				(type default)
			)
			(layer "B.Fab")
		)
		(fp_line
			(start 0.12065 0.3048)
			(end 0.67945 0.3048)
			(stroke
				(width 0.1)
				(type default)
			)
			(layer "B.Fab")
		)
		(fp_line
			(start 0.12065 0.2794)
			(end 0.12065 0.3048)
			(stroke
				(width 0.1)
				(type default)
			)
			(layer "B.Fab")
		)
		(fp_line
			(start 0.12065 -0.2794)
			(end -0.12065 -0.2794)
			(stroke
				(width 0.1)
				(type default)
			)
			(layer "B.Fab")
		)
		(fp_line
			(start 0.12065 -0.305054)
			(end 0.12065 -0.2794)
			(stroke
				(width 0.1)
				(type default)
			)
			(layer "B.Fab")
		)
		(fp_line
			(start -0.120396 0.3048)
			(end -0.120396 0.2794)
			(stroke
				(width 0.1)
				(type default)
			)
			(layer "B.Fab")
		)
		(fp_line
			(start -0.120396 0.2794)
			(end 0.12065 0.2794)
			(stroke
				(width 0.1)
				(type default)
			)
			(layer "B.Fab")
		)
		(fp_line
			(start -0.12065 -0.2794)
			(end -0.12065 -0.3048)
			(stroke
				(width 0.1)
				(type default)
			)
			(layer "B.Fab")
		)
		(fp_line
			(start -0.12065 -0.3048)
			(end -0.67945 -0.3048)
			(stroke
				(width 0.1)
				(type default)
			)
			(layer "B.Fab")
		)
		(fp_line
			(start -0.67945 0.3048)
			(end -0.120396 0.3048)
			(stroke
				(width 0.1)
				(type default)
			)
			(layer "B.Fab")
		)
		(fp_line
			(start -0.67945 -0.3048)
			(end -0.67945 0.3048)
			(stroke
				(width 0.1)
				(type default)
			)
			(layer "B.Fab")
		)
		(pad "1" smd circle
			(at 0.40005 0)
			(size 0 0)
			(layers "B.Cu" "B.Mask" "B.Paste")
			(net "PVDDIO_P1")
		)
		(pad "2" smd circle
			(at -0.40005 0)
			(size 0 0)
			(layers "B.Cu" "B.Mask" "B.Paste")
			(net "GND")
		)
	)
	(footprint ""
		(layer "B.Cu")
		(at 218.059 -336.296 180)
		(property "Reference" "R6736"
			(at 0 0 0)
			(layer "B.SilkS")
			(hide yes)
			(effects
				(font
					(size 1.27 1.27)
				)
				(justify mirror)
			)
		)
		(property "Value" ""
			(at 0 0 0)
			(layer "B.Fab")
			(effects
				(font
					(size 1.27 1.27)
				)
				(justify mirror)
			)
		)
		(duplicate_pad_numbers_are_jumpers no)
		(fp_line
			(start 0.32512 0.175006)
			(end 0.32512 -0.175006)
			(stroke
				(width 0.1)
				(type default)
			)
			(layer "B.Fab")
		)
		(fp_line
			(start 0.32512 -0.175006)
			(end -0.32512 -0.175006)
			(stroke
				(width 0.1)
				(type default)
			)
			(layer "B.Fab")
		)
		(fp_line
			(start -0.32512 0.175006)
			(end 0.32512 0.175006)
			(stroke
				(width 0.1)
				(type default)
			)
			(layer "B.Fab")
		)
		(fp_line
			(start -0.32512 -0.175006)
			(end -0.32512 0.175006)
			(stroke
				(width 0.1)
				(type default)
			)
			(layer "B.Fab")
		)
		(pad "1" smd rect
			(at 0.2667 0)
			(size 0.3048 0.381)
			(layers "B.Cu" "B.Mask" "B.Paste")
			(net "SMB_RT_CPU1_P1_R_SDA")
		)
		(pad "2" smd rect
			(at -0.2667 0 180)
			(size 0.3048 0.381)
			(layers "B.Cu" "B.Mask" "B.Paste")
			(net "SMB_RT_CPU1_P1_SDA")
		)
	)
	(footprint ""
		(layer "B.Cu")
		(at 374.0785 -395.148562 90)
		(property "Reference" "C1024"
			(at 0 0 90)
			(layer "B.SilkS")
			(hide yes)
			(effects
				(font
					(size 1.27 1.27)
				)
				(justify mirror)
			)
		)
		(property "Value" ""
			(at 0 0 90)
			(layer "B.Fab")
			(effects
				(font
					(size 1.27 1.27)
				)
				(justify mirror)
			)
		)
		(duplicate_pad_numbers_are_jumpers no)
		(fp_line
			(start 0.299974 -0.150114)
			(end -0.299974 -0.150114)
			(stroke
				(width 0.1)
				(type default)
			)
			(layer "B.Fab")
		)
		(fp_line
			(start -0.299974 -0.150114)
			(end -0.299974 0.150114)
			(stroke
				(width 0.1)
				(type default)
			)
			(layer "B.Fab")
		)
		(fp_line
			(start 0.299974 0.150114)
			(end 0.299974 -0.150114)
			(stroke
				(width 0.1)
				(type default)
			)
			(layer "B.Fab")
		)
		(fp_line
			(start -0.299974 0.150114)
			(end 0.299974 0.150114)
			(stroke
				(width 0.1)
				(type default)
			)
			(layer "B.Fab")
		)
		(pad "1" smd rect
			(at 0.2667 0 270)
			(size 0.3048 0.381)
			(layers "B.Cu" "B.Mask" "B.Paste")
			(net "P0V9_CPU0_RT3_2A")
		)
		(pad "2" smd rect
			(at -0.2667 0 270)
			(size 0.3048 0.381)
			(layers "B.Cu" "B.Mask" "B.Paste")
			(net "GND")
		)
	)
	(footprint ""
		(layer "B.Cu")
		(at 308.1782 -395.148562 90)
		(property "Reference" "C542"
			(at 0 0 90)
			(layer "B.SilkS")
			(hide yes)
			(effects
				(font
					(size 1.27 1.27)
				)
				(justify mirror)
			)
		)
		(property "Value" ""
			(at 0 0 90)
			(layer "B.Fab")
			(effects
				(font
					(size 1.27 1.27)
				)
				(justify mirror)
			)
		)
		(duplicate_pad_numbers_are_jumpers no)
		(fp_line
			(start 0.299974 -0.150114)
			(end -0.299974 -0.150114)
			(stroke
				(width 0.1)
				(type default)
			)
			(layer "B.Fab")
		)
		(fp_line
			(start -0.299974 -0.150114)
			(end -0.299974 0.150114)
			(stroke
				(width 0.1)
				(type default)
			)
			(layer "B.Fab")
		)
		(fp_line
			(start 0.299974 0.150114)
			(end 0.299974 -0.150114)
			(stroke
				(width 0.1)
				(type default)
			)
			(layer "B.Fab")
		)
		(fp_line
			(start -0.299974 0.150114)
			(end 0.299974 0.150114)
			(stroke
				(width 0.1)
				(type default)
			)
			(layer "B.Fab")
		)
		(pad "1" smd rect
			(at 0.2667 0 270)
			(size 0.3048 0.381)
			(layers "B.Cu" "B.Mask" "B.Paste")
			(net "P0V9_CPU0_RT0_2A_2D")
		)
		(pad "2" smd rect
			(at -0.2667 0 270)
			(size 0.3048 0.381)
			(layers "B.Cu" "B.Mask" "B.Paste")
			(net "GND")
		)
	)
	(footprint ""
		(layer "B.Cu")
		(at 358.796082 -259.845048 180)
		(property "Reference" "C2621"
			(at 0 0 0)
			(layer "B.SilkS")
			(hide yes)
			(effects
				(font
					(size 1.27 1.27)
				)
				(justify mirror)
			)
		)
		(property "Value" ""
			(at 0 0 0)
			(layer "B.Fab")
			(effects
				(font
					(size 1.27 1.27)
				)
				(justify mirror)
			)
		)
		(duplicate_pad_numbers_are_jumpers no)
		(fp_line
			(start 0.7874 0.4064)
			(end 0.7874 -0.4064)
			(stroke
				(width 0.1524)
				(type default)
			)
			(layer "B.SilkS")
		)
		(fp_line
			(start 0.7874 -0.4064)
			(end -0.7874 -0.4064)
			(stroke
				(width 0.1524)
				(type default)
			)
			(layer "B.SilkS")
		)
		(fp_line
			(start -0.7874 0.4064)
			(end 0.7874 0.4064)
			(stroke
				(width 0.1524)
				(type default)
			)
			(layer "B.SilkS")
		)
		(fp_line
			(start -0.7874 -0.4064)
			(end -0.7874 0.4064)
			(stroke
				(width 0.1524)
				(type default)
			)
			(layer "B.SilkS")
		)
		(fp_line
			(start 0.67945 0.3048)
			(end 0.67945 -0.305054)
			(stroke
				(width 0.1)
				(type default)
			)
			(layer "B.Fab")
		)
		(fp_line
			(start 0.67945 -0.305054)
			(end 0.12065 -0.305054)
			(stroke
				(width 0.1)
				(type default)
			)
			(layer "B.Fab")
		)
		(fp_line
			(start 0.12065 0.3048)
			(end 0.67945 0.3048)
			(stroke
				(width 0.1)
				(type default)
			)
			(layer "B.Fab")
		)
		(fp_line
			(start 0.12065 0.2794)
			(end 0.12065 0.3048)
			(stroke
				(width 0.1)
				(type default)
			)
			(layer "B.Fab")
		)
		(fp_line
			(start 0.12065 -0.2794)
			(end -0.12065 -0.2794)
			(stroke
				(width 0.1)
				(type default)
			)
			(layer "B.Fab")
		)
		(fp_line
			(start 0.12065 -0.305054)
			(end 0.12065 -0.2794)
			(stroke
				(width 0.1)
				(type default)
			)
			(layer "B.Fab")
		)
		(fp_line
			(start -0.120396 0.3048)
			(end -0.120396 0.2794)
			(stroke
				(width 0.1)
				(type default)
			)
			(layer "B.Fab")
		)
		(fp_line
			(start -0.120396 0.2794)
			(end 0.12065 0.2794)
			(stroke
				(width 0.1)
				(type default)
			)
			(layer "B.Fab")
		)
		(fp_line
			(start -0.12065 -0.2794)
			(end -0.12065 -0.3048)
			(stroke
				(width 0.1)
				(type default)
			)
			(layer "B.Fab")
		)
		(fp_line
			(start -0.12065 -0.3048)
			(end -0.67945 -0.3048)
			(stroke
				(width 0.1)
				(type default)
			)
			(layer "B.Fab")
		)
		(fp_line
			(start -0.67945 0.3048)
			(end -0.120396 0.3048)
			(stroke
				(width 0.1)
				(type default)
			)
			(layer "B.Fab")
		)
		(fp_line
			(start -0.67945 -0.3048)
			(end -0.67945 0.3048)
			(stroke
				(width 0.1)
				(type default)
			)
			(layer "B.Fab")
		)
		(pad "1" smd circle
			(at 0.40005 0)
			(size 0 0)
			(layers "B.Cu" "B.Mask" "B.Paste")
			(net "PVDD11_S3_P0")
		)
		(pad "2" smd circle
			(at -0.40005 0)
			(size 0 0)
			(layers "B.Cu" "B.Mask" "B.Paste")
			(net "GND")
		)
	)
)
